(kicad_pcb
	(version 20241229)
	(generator "pcbnew")
	(generator_version "9.0")
	(general
		(thickness 1.63)
		(legacy_teardrops no)
	)
	(paper "A4")
	(title_block
		(title "CM4 Baseboard")
		(date "2026-01-05")
		(rev "1.1.1")
		(company "Antmicro Ltd")
		(comment 1 "www.antmicro.com")
		(comment 9 "footprints 317-320 of 506")
	)
	(layers
		(0 "F.Cu" signal)
		(4 "In1.Cu" power)
		(6 "In2.Cu" power)
		(8 "In3.Cu" signal)
		(10 "In4.Cu" signal)
		(2 "B.Cu" signal)
		(9 "F.Adhes" user "F.Adhesive")
		(11 "B.Adhes" user "B.Adhesive")
		(13 "F.Paste" user)
		(15 "B.Paste" user)
		(5 "F.SilkS" user "F.Silkscreen")
		(7 "B.SilkS" user "B.Silkscreen")
		(1 "F.Mask" user)
		(3 "B.Mask" user)
		(17 "Dwgs.User" user "User.Drawings")
		(19 "Cmts.User" user "User.Comments")
		(21 "Eco1.User" user "User.Eco1")
		(23 "Eco2.User" user "User.Eco2")
		(25 "Edge.Cuts" user)
		(27 "Margin" user)
		(31 "F.CrtYd" user "F.Courtyard")
		(29 "B.CrtYd" user "B.Courtyard")
		(35 "F.Fab" user)
		(33 "B.Fab" user)
	)
	(footprint "antmicro-footprints:HDMI-A_Receptacle_WE_685119134923"
		(layer "F.Cu")
		(at 109.417962 117.3365)
		(property "Reference" "J702"
			(at 8.41 -2.89 90)
			(layer "F.SilkS")
			(effects
				(font
					(size 0.7 0.7)
					(thickness 0.15)
				)
				(justify left bottom)
			)
		)
		(property "Value" "HDMI-A_WE_685119134923"
			(at 0 7.8 0)
			(layer "F.Fab")
			(effects
				(font
					(size 0.7 0.7)
					(thickness 0.15)
				)
				(justify left bottom)
			)
		)
		(property "Datasheet" "https://www.we-online.com/components/products/datasheet/685119134923.pdf"
			(at 0 0 0)
			(layer "F.Fab")
			(hide yes)
			(effects
				(font
					(size 1.27 1.27)
					(thickness 0.15)
				)
			)
		)
		(property "MPN" "685119134923"
			(at 0 0 0)
			(unlocked yes)
			(layer "F.Fab")
			(hide yes)
			(effects
				(font
					(size 1 1)
					(thickness 0.15)
				)
			)
		)
		(property "Manufacturer" "Würth Elektronik"
			(at 0 0 0)
			(unlocked yes)
			(layer "F.Fab")
			(hide yes)
			(effects
				(font
					(size 1 1)
					(thickness 0.15)
				)
			)
		)
		(property "Author" "Antmicro"
			(at 0 0 0)
			(unlocked yes)
			(layer "F.Fab")
			(hide yes)
			(effects
				(font
					(size 1 1)
					(thickness 0.15)
				)
			)
		)
		(property "License" "Apache-2.0"
			(at 0 0 0)
			(unlocked yes)
			(layer "F.Fab")
			(hide yes)
			(effects
				(font
					(size 1 1)
					(thickness 0.15)
				)
			)
		)
		(property ki_fp_filters "685119134923")
		(sheetname "/Display/")
		(sheetfile "display.kicad_sch")
		(attr smd)
		(fp_line
			(start -7.55 -0.125)
			(end -7.55 2.65)
			(stroke
				(width 0.12)
				(type solid)
			)
			(layer "F.SilkS")
		)
		(fp_line
			(start -4.85 5.65)
			(end -5.8 5.65)
			(stroke
				(width 0.12)
				(type solid)
			)
			(layer "F.SilkS")
		)
		(fp_line
			(start 5.7 5.65)
			(end 4.75 5.65)
			(stroke
				(width 0.12)
				(type solid)
			)
			(layer "F.SilkS")
		)
		(fp_line
			(start 7.55 2.75)
			(end 7.55 -0.15)
			(stroke
				(width 0.12)
				(type solid)
			)
			(layer "F.SilkS")
		)
		(fp_circle
			(center -4.9 5.9)
			(end -4.85 5.9)
			(stroke
				(width 0.15)
				(type solid)
			)
			(fill no)
			(layer "F.SilkS")
		)
		(fp_rect
			(start -8.05 -6.32)
			(end 7.949 6.78)
			(stroke
				(width 0.05)
				(type solid)
			)
			(fill no)
			(layer "F.CrtYd")
		)
		(fp_line
			(start -7.05 -5.616)
			(end 6.95 -5.616)
			(stroke
				(width 0.15)
				(type solid)
			)
			(layer "F.Fab")
		)
		(fp_line
			(start -7.05 5.525)
			(end -7.05 -5.616)
			(stroke
				(width 0.15)
				(type solid)
			)
			(layer "F.Fab")
		)
		(fp_line
			(start -7.05 5.525)
			(end -6.05 6.525)
			(stroke
				(width 0.15)
				(type solid)
			)
			(layer "F.Fab")
		)
		(fp_line
			(start 6.95 6.535)
			(end -6.05 6.535)
			(stroke
				(width 0.15)
				(type solid)
			)
			(layer "F.Fab")
		)
		(fp_line
			(start 6.95 6.535)
			(end 6.95 -5.616)
			(stroke
				(width 0.15)
				(type solid)
			)
			(layer "F.Fab")
		)
		(fp_text user "License: Apache-2.0"
			(at -8 12.5 0)
			(layer "F.Fab")
			(effects
				(font
					(size 0.7 0.7)
					(thickness 0.15)
				)
				(justify left bottom)
			)
		)
		(fp_text user "Author: Antmicro"
			(at -8 11 0)
			(layer "F.Fab")
			(effects
				(font
					(size 0.7 0.7)
					(thickness 0.15)
				)
				(justify left bottom)
			)
		)
		(fp_text user "${REFERENCE}"
			(at -8 9.5 0)
			(layer "F.Fab")
			(effects
				(font
					(size 0.7 0.7)
					(thickness 0.15)
				)
				(justify left bottom)
			)
		)
		(pad "1" smd rect
			(at -4.55 5.224)
			(size 0.28 2.6)
			(layers "F.Cu" "F.Mask" "F.Paste")
			(net 16 "/Compute module/HDMI.D2_P")
			(pinfunction "D2+")
			(pintype "bidirectional")
		)
		(pad "2" smd rect
			(at -4.05 5.224)
			(size 0.28 2.6)
			(layers "F.Cu" "F.Mask" "F.Paste")
			(net 3 "GND")
			(pinfunction "D2S")
			(pintype "passive")
		)
		(pad "3" smd rect
			(at -3.551 5.224)
			(size 0.28 2.6)
			(layers "F.Cu" "F.Mask" "F.Paste")
			(net 15 "/Compute module/HDMI.D2_N")
			(pinfunction "D2-")
			(pintype "bidirectional")
		)
		(pad "4" smd rect
			(at -3.051 5.224)
			(size 0.28 2.6)
			(layers "F.Cu" "F.Mask" "F.Paste")
			(net 14 "/Compute module/HDMI.D1_P")
			(pinfunction "D1+")
			(pintype "bidirectional")
		)
		(pad "5" smd rect
			(at -2.551 5.224)
			(size 0.28 2.6)
			(layers "F.Cu" "F.Mask" "F.Paste")
			(net 3 "GND")
			(pinfunction "D1S")
			(pintype "passive")
		)
		(pad "6" smd rect
			(at -2.05 5.224)
			(size 0.28 2.6)
			(layers "F.Cu" "F.Mask" "F.Paste")
			(net 13 "/Compute module/HDMI.D1_N")
			(pinfunction "D1-")
			(pintype "bidirectional")
		)
		(pad "7" smd rect
			(at -1.551 5.224)
			(size 0.28 2.6)
			(layers "F.Cu" "F.Mask" "F.Paste")
			(net 35 "/Compute module/HDMI.D0_P")
			(pinfunction "D0+")
			(pintype "bidirectional")
		)
		(pad "8" smd rect
			(at -1.051 5.224)
			(size 0.28 2.6)
			(layers "F.Cu" "F.Mask" "F.Paste")
			(net 3 "GND")
			(pinfunction "D0S")
			(pintype "passive")
		)
		(pad "9" smd rect
			(at -0.551 5.224)
			(size 0.28 2.6)
			(layers "F.Cu" "F.Mask" "F.Paste")
			(net 34 "/Compute module/HDMI.D0_N")
			(pinfunction "D0-")
			(pintype "bidirectional")
		)
		(pad "10" smd rect
			(at -0.051 5.224)
			(size 0.28 2.6)
			(layers "F.Cu" "F.Mask" "F.Paste")
			(net 25 "/Compute module/HDMI.CLK_P")
			(pinfunction "CK+")
			(pintype "bidirectional")
		)
		(pad "11" smd rect
			(at 0.45 5.224)
			(size 0.28 2.6)
			(layers "F.Cu" "F.Mask" "F.Paste")
			(net 3 "GND")
			(pinfunction "CKS")
			(pintype "passive")
		)
		(pad "12" smd rect
			(at 0.95 5.224)
			(size 0.28 2.6)
			(layers "F.Cu" "F.Mask" "F.Paste")
			(net 23 "/Compute module/HDMI.CLK_N")
			(pinfunction "CK-")
			(pintype "bidirectional")
		)
		(pad "13" smd rect
			(at 1.449 5.224)
			(size 0.28 2.6)
			(layers "F.Cu" "F.Mask" "F.Paste")
			(net 451 "/Display/CEC")
			(pinfunction "CEC")
			(pintype "bidirectional")
		)
		(pad "14" smd rect
			(at 1.949 5.224)
			(size 0.28 2.6)
			(layers "F.Cu" "F.Mask" "F.Paste")
			(net 318 "unconnected-(J702-UTILITY{slash}HEAC+-Pad14)")
			(pinfunction "UTILITY/HEAC+")
			(pintype "bidirectional+no_connect")
		)
		(pad "15" smd rect
			(at 2.45 5.224)
			(size 0.28 2.6)
			(layers "F.Cu" "F.Mask" "F.Paste")
			(net 452 "/Display/SCL")
			(pinfunction "SCL")
			(pintype "bidirectional")
		)
		(pad "16" smd rect
			(at 2.95 5.224)
			(size 0.28 2.6)
			(layers "F.Cu" "F.Mask" "F.Paste")
			(net 453 "/Display/SDA")
			(pinfunction "SDA")
			(pintype "bidirectional")
		)
		(pad "17" smd rect
			(at 3.45 5.224)
			(size 0.28 2.6)
			(layers "F.Cu" "F.Mask" "F.Paste")
			(net 3 "GND")
			(pinfunction "GND")
			(pintype "power_in")
		)
		(pad "18" smd rect
			(at 3.95 5.224)
			(size 0.28 2.6)
			(layers "F.Cu" "F.Mask" "F.Paste")
			(net 119 "Net-(D710-C)")
			(pinfunction "+5V")
			(pintype "power_in")
		)
		(pad "19" smd rect
			(at 4.45 5.224)
			(size 0.28 2.6)
			(layers "F.Cu" "F.Mask" "F.Paste")
			(net 454 "/Display/HPD")
			(pinfunction "HPD/HEAC-")
			(pintype "bidirectional")
		)
		(pad "SH" thru_hole oval
			(at -7.3 -1.577)
			(size 1.5 2.7)
			(drill oval 0.9 2.1)
			(layers "*.Cu" "*.Mask")
			(remove_unused_layers no)
			(net 3 "GND")
			(pinfunction "SH")
			(pintype "passive")
		)
		(pad "SH" thru_hole oval
			(at -7.3 4.424)
			(size 1.5 3.3)
			(drill oval 0.9 2.7)
			(layers "*.Cu" "*.Mask")
			(remove_unused_layers no)
			(net 3 "GND")
			(pinfunction "SH")
			(pintype "passive")
		)
		(pad "SH" thru_hole oval
			(at 7.2 -1.577)
			(size 1.5 2.7)
			(drill oval 0.9 2.1)
			(layers "*.Cu" "*.Mask")
			(remove_unused_layers no)
			(net 3 "GND")
			(pinfunction "SH")
			(pintype "passive")
		)
		(pad "SH" thru_hole oval
			(at 7.2 4.424)
			(size 1.5 3.3)
			(drill oval 0.9 2.7)
			(layers "*.Cu" "*.Mask")
			(remove_unused_layers no)
			(net 3 "GND")
			(pinfunction "SH")
			(pintype "passive")
		)
	)
	(footprint "antmicro-footprints:R_0402_1005Metric"
		(layer "F.Cu")
		(at 72.867962 167.4115)
		(descr "Resistor SMD 0402")
		(tags "resistor SMD 0402")
		(property "Reference" "R806"
			(at -1.887962 -1.475 0)
			(layer "F.SilkS")
			(effects
				(font
					(size 0.7 0.7)
					(thickness 0.15)
				)
				(justify left bottom)
			)
		)
		(property "Value" "R_10k_0402"
			(at -1.011843 1.772047 0)
			(layer "F.Fab")
			(effects
				(font
					(size 0.7 0.7)
					(thickness 0.15)
				)
				(justify left bottom)
			)
		)
		(property "Datasheet" "https://www.bourns.com/docs/product-datasheets/cr.pdf"
			(at 0 0 0)
			(layer "F.Fab")
			(hide yes)
			(effects
				(font
					(size 1.27 1.27)
					(thickness 0.15)
				)
			)
		)
		(property "MPN" "CR0402-FX-1002GLF"
			(at 0 0 0)
			(unlocked yes)
			(layer "F.Fab")
			(hide yes)
			(effects
				(font
					(size 1 1)
					(thickness 0.15)
				)
			)
		)
		(property "Manufacturer" "Bourns"
			(at 0 0 0)
			(unlocked yes)
			(layer "F.Fab")
			(hide yes)
			(effects
				(font
					(size 1 1)
					(thickness 0.15)
				)
			)
		)
		(property "License" "Apache-2.0"
			(at 0 0 0)
			(unlocked yes)
			(layer "F.Fab")
			(hide yes)
			(effects
				(font
					(size 1 1)
					(thickness 0.15)
				)
			)
		)
		(property "Author" "Antmicro"
			(at 0 0 0)
			(unlocked yes)
			(layer "F.Fab")
			(hide yes)
			(effects
				(font
					(size 1 1)
					(thickness 0.15)
				)
			)
		)
		(property "Val" "10k"
			(at 0 0 0)
			(unlocked yes)
			(layer "F.Fab")
			(hide yes)
			(effects
				(font
					(size 1 1)
					(thickness 0.15)
				)
			)
		)
		(property "Tolerance" "1%"
			(at 0 0 0)
			(unlocked yes)
			(layer "F.Fab")
			(hide yes)
			(effects
				(font
					(size 1 1)
					(thickness 0.15)
				)
			)
		)
		(sheetname "/Peripherals/")
		(sheetfile "peripherals.kicad_sch")
		(attr smd)
		(fp_rect
			(start -0.925 -0.47)
			(end 0.925 0.47)
			(stroke
				(width 0.05)
				(type default)
			)
			(fill no)
			(layer "F.CrtYd")
		)
		(fp_rect
			(start -0.5 -0.25)
			(end 0.5 0.25)
			(stroke
				(width 0.15)
				(type solid)
			)
			(fill no)
			(layer "F.Fab")
		)
		(fp_text user "License: Apache-2.0"
			(at -0.95 5.169 0)
			(layer "F.Fab")
			(effects
				(font
					(size 0.7 0.7)
					(thickness 0.15)
				)
				(justify left bottom)
			)
		)
		(fp_text user "Author: Antmicro"
			(at -0.95 4.169 0)
			(layer "F.Fab")
			(effects
				(font
					(size 0.7 0.7)
					(thickness 0.15)
				)
				(justify left bottom)
			)
		)
		(fp_text user "${REFERENCE}"
			(at -0.95 3.168 0)
			(layer "F.Fab")
			(effects
				(font
					(size 0.7 0.7)
					(thickness 0.15)
				)
				(justify left bottom)
			)
		)
		(pad "1" smd roundrect
			(at -0.48 0)
			(size 0.59 0.64)
			(layers "F.Cu" "F.Mask" "F.Paste")
			(roundrect_rratio 0.25)
			(net 3 "GND")
			(pintype "passive")
		)
		(pad "2" smd roundrect
			(at 0.48 0)
			(size 0.59 0.64)
			(layers "F.Cu" "F.Mask" "F.Paste")
			(roundrect_rratio 0.25)
			(net 375 "Net-(U801-I2C_ADR1)")
			(pintype "passive")
		)
	)
	(footprint "antmicro-footprints:R_0402_1005Metric"
		(layer "F.Cu")
		(at 96.117962 129.2165)
		(descr "Resistor SMD 0402")
		(tags "resistor SMD 0402")
		(property "Reference" "R905"
			(at -1.65 1.2 0)
			(layer "F.SilkS")
			(effects
				(font
					(size 0.7 0.7)
					(thickness 0.15)
				)
				(justify left bottom)
			)
		)
		(property "Value" "R_4k7_0402"
			(at -1.011843 1.772047 0)
			(layer "F.Fab")
			(effects
				(font
					(size 0.7 0.7)
					(thickness 0.15)
				)
				(justify left bottom)
			)
		)
		(property "Datasheet" "https://www.bourns.com/docs/product-datasheets/cr.pdf"
			(at 0 0 0)
			(layer "F.Fab")
			(hide yes)
			(effects
				(font
					(size 1.27 1.27)
					(thickness 0.15)
				)
			)
		)
		(property "Manufacturer" "Bourns"
			(at 0 0 0)
			(unlocked yes)
			(layer "F.Fab")
			(hide yes)
			(effects
				(font
					(size 1 1)
					(thickness 0.15)
				)
			)
		)
		(property "MPN" "CR0402-FX-4701GLF"
			(at 0 0 0)
			(unlocked yes)
			(layer "F.Fab")
			(hide yes)
			(effects
				(font
					(size 1 1)
					(thickness 0.15)
				)
			)
		)
		(property "Val" "4k7"
			(at 0 0 0)
			(unlocked yes)
			(layer "F.Fab")
			(hide yes)
			(effects
				(font
					(size 1 1)
					(thickness 0.15)
				)
			)
		)
		(property "License" "Apache-2.0"
			(at 0 0 0)
			(unlocked yes)
			(layer "F.Fab")
			(hide yes)
			(effects
				(font
					(size 1 1)
					(thickness 0.15)
				)
			)
		)
		(property "Author" "Antmicro"
			(at 0 0 0)
			(unlocked yes)
			(layer "F.Fab")
			(hide yes)
			(effects
				(font
					(size 1 1)
					(thickness 0.15)
				)
			)
		)
		(property "Tolerance" "1%"
			(at 0 0 0)
			(unlocked yes)
			(layer "F.Fab")
			(hide yes)
			(effects
				(font
					(size 1 1)
					(thickness 0.15)
				)
			)
		)
		(sheetname "/USB/")
		(sheetfile "usb.kicad_sch")
		(attr smd)
		(fp_rect
			(start -0.925 -0.47)
			(end 0.925 0.47)
			(stroke
				(width 0.05)
				(type default)
			)
			(fill no)
			(layer "F.CrtYd")
		)
		(fp_rect
			(start -0.5 -0.25)
			(end 0.5 0.25)
			(stroke
				(width 0.15)
				(type solid)
			)
			(fill no)
			(layer "F.Fab")
		)
		(fp_text user "${REFERENCE}"
			(at -0.95 3.168 0)
			(layer "F.Fab")
			(effects
				(font
					(size 0.7 0.7)
					(thickness 0.15)
				)
				(justify left bottom)
			)
		)
		(fp_text user "Author: Antmicro"
			(at -0.95 4.169 0)
			(layer "F.Fab")
			(effects
				(font
					(size 0.7 0.7)
					(thickness 0.15)
				)
				(justify left bottom)
			)
		)
		(fp_text user "License: Apache-2.0"
			(at -0.95 5.169 0)
			(layer "F.Fab")
			(effects
				(font
					(size 0.7 0.7)
					(thickness 0.15)
				)
				(justify left bottom)
			)
		)
		(pad "1" smd roundrect
			(at -0.48 0)
			(size 0.59 0.64)
			(layers "F.Cu" "F.Mask" "F.Paste")
			(roundrect_rratio 0.25)
			(net 3 "GND")
			(pintype "passive")
		)
		(pad "2" smd roundrect
			(at 0.48 0)
			(size 0.59 0.64)
			(layers "F.Cu" "F.Mask" "F.Paste")
			(roundrect_rratio 0.25)
			(net 376 "Net-(U901-ISET)")
			(pintype "passive")
		)
	)
	(footprint "antmicro-footprints:LED_0603_1608Metric_G"
		(layer "F.Cu")
		(at 58.467962 134.9865 90)
		(descr "LED SMD 0603 Green")
		(tags "LED SMD 0603 Green")
		(property "Reference" "D404"
			(at -1.355 3.3 90)
			(layer "F.SilkS")
			(effects
				(font
					(size 0.7 0.7)
					(thickness 0.15)
				)
				(justify left bottom)
			)
		)
		(property "Value" "LED_G_0603_KP-1608CGCK"
			(at -0.001 1.599 90)
			(layer "F.Fab")
			(effects
				(font
					(size 0.7 0.7)
					(thickness 0.15)
				)
				(justify left bottom)
			)
		)
		(property "Datasheet" "http://www.kingbright.com/attachments/file/psearch//000/00/00/KP-1608CGCK(Ver.23B).pdf"
			(at 0 0 90)
			(layer "F.Fab")
			(hide yes)
			(effects
				(font
					(size 1.27 1.27)
					(thickness 0.15)
				)
			)
		)
		(property "MPN" "KP-1608CGCK"
			(at 0 0 90)
			(unlocked yes)
			(layer "F.Fab")
			(hide yes)
			(effects
				(font
					(size 1 1)
					(thickness 0.15)
				)
			)
		)
		(property "Manufacturer" "Kingbright"
			(at 0 0 90)
			(unlocked yes)
			(layer "F.Fab")
			(hide yes)
			(effects
				(font
					(size 1 1)
					(thickness 0.15)
				)
			)
		)
		(property "Color" "Green"
			(at 0 0 90)
			(unlocked yes)
			(layer "F.Fab")
			(hide yes)
			(effects
				(font
					(size 1 1)
					(thickness 0.15)
				)
			)
		)
		(property "Author" "Antmicro"
			(at 0 0 90)
			(unlocked yes)
			(layer "F.Fab")
			(hide yes)
			(effects
				(font
					(size 1 1)
					(thickness 0.15)
				)
			)
		)
		(property "License" "Apache-2.0"
			(at 0 0 90)
			(unlocked yes)
			(layer "F.Fab")
			(hide yes)
			(effects
				(font
					(size 1 1)
					(thickness 0.15)
				)
			)
		)
		(sheetname "/Ethernet/")
		(sheetfile "ethernet.kicad_sch")
		(attr smd)
		(fp_line
			(start 0.22 -0.35)
			(end -0.22 -0.35)
			(stroke
				(width 0.15)
				(type solid)
			)
			(layer "F.SilkS")
		)
		(fp_line
			(start -1.18 -0.319)
			(end -1.18 0.321)
			(stroke
				(width 0.15)
				(type solid)
			)
			(layer "F.SilkS")
		)
		(fp_line
			(start 0.105328 0.001008)
			(end 0.24 0.001)
			(stroke
				(width 0.1)
				(type solid)
			)
			(layer "F.SilkS")
		)
		(fp_line
			(start -0.094672 0.001008)
			(end 0.105328 -0.198992)
			(stroke
				(width 0.1)
				(type solid)
			)
			(layer "F.SilkS")
		)
		(fp_line
			(start -0.094672 0.001008)
			(end -0.24 0.001008)
			(stroke
				(width 0.1)
				(type solid)
			)
			(layer "F.SilkS")
		)
		(fp_line
			(start 0.105328 0.201008)
			(end 0.105328 -0.198992)
			(stroke
				(width 0.1)
				(type solid)
			)
			(layer "F.SilkS")
		)
		(fp_line
			(start 0.105328 0.201008)
			(end -0.094672 0.001008)
			(stroke
				(width 0.1)
				(type solid)
			)
			(layer "F.SilkS")
		)
		(fp_line
			(start -0.094672 0.201008)
			(end -0.094672 -0.198992)
			(stroke
				(width 0.1)
				(type solid)
			)
			(layer "F.SilkS")
		)
		(fp_line
			(start 0.22 0.35)
			(end -0.22 0.35)
			(stroke
				(width 0.15)
				(type solid)
			)
			(layer "F.SilkS")
		)
		(fp_rect
			(start 1.25 0.65)
			(end -1.25 -0.65)
			(stroke
				(width 0.05)
				(type solid)
			)
			(fill no)
			(layer "F.CrtYd")
		)
		(fp_line
			(start 0.201 -0.202)
			(end -0.101 0)
			(stroke
				(width 0.15)
				(type solid)
			)
			(layer "F.Fab")
		)
		(fp_line
			(start -0.199 -0.202)
			(end -0.199 0.1)
			(stroke
				(width 0.15)
				(type solid)
			)
			(layer "F.Fab")
		)
		(fp_line
			(start 0.599 0)
			(end 0.201 0)
			(stroke
				(width 0.15)
				(type solid)
			)
			(layer "F.Fab")
		)
		(fp_line
			(start 0.201 0)
			(end 0.201 -0.202)
			(stroke
				(width 0.15)
				(type solid)
			)
			(layer "F.Fab")
		)
		(fp_line
			(start -0.101 0)
			(end 0.201 0.2)
			(stroke
				(width 0.15)
				(type solid)
			)
			(layer "F.Fab")
		)
		(fp_line
			(start -0.199 0)
			(end -0.597 0)
			(stroke
				(width 0.15)
				(type solid)
			)
			(layer "F.Fab")
		)
		(fp_line
			(start 0.201 0.2)
			(end 0.201 0)
			(stroke
				(width 0.15)
				(type solid)
			)
			(layer "F.Fab")
		)
		(fp_line
			(start -0.199 0.2)
			(end -0.199 0.1)
			(stroke
				(width 0.15)
				(type solid)
			)
			(layer "F.Fab")
		)
		(fp_rect
			(start 0.848 0.4)
			(end -0.85 -0.402)
			(stroke
				(width 0.15)
				(type solid)
			)
			(fill no)
			(layer "F.Fab")
		)
		(fp_text user "License: Apache-2.0"
			(at -1.4224 3.599 90)
			(layer "F.Fab")
			(effects
				(font
					(size 0.7 0.7)
					(thickness 0.15)
				)
				(justify left bottom)
			)
		)
		(fp_text user "${REFERENCE}"
			(at -1.4224 5.999 90)
			(layer "F.Fab")
			(effects
				(font
					(size 0.7 0.7)
					(thickness 0.15)
				)
				(justify left bottom)
			)
		)
		(fp_text user "Author: Antmicro"
			(at -1.4224 4.799 90)
			(layer "F.Fab")
			(effects
				(font
					(size 0.7 0.7)
					(thickness 0.15)
				)
				(justify left bottom)
			)
		)
		(pad "1" smd roundrect
			(at -0.7 0 270)
			(size 0.8 1)
			(layers "F.Cu" "F.Mask" "F.Paste")
			(roundrect_rratio 0.2)
			(net 1 "GNDD")
			(pinfunction "C")
			(pintype "passive")
		)
		(pad "2" smd roundrect
			(at 0.7 0 270)
			(size 0.8 1)
			(layers "F.Cu" "F.Mask" "F.Paste")
			(roundrect_rratio 0.2)
			(net 477 "Net-(D404-A)")
			(pinfunction "A")
			(pintype "passive")
		)
	)
)
